# S9S_MB_2U (Grand Teton) — schematic netlist excerpt (pin names and nets, part order shuffled) for the footprints in the layout excerpt that follows; sources: Cadence DE-HDL packaged netlist, KiCad conversion of 03242023_DA0F0TMBIJ0_F0T_Motherboard_J_brd_V01_OCP.brd

R250  Q_RES  240 1% EMPTY  pkg 0402LF  page 120 : A = PVNN_TERM_CPU0 ; B = FM_S3M_CPU0_LVC1_GPIO_1
PR531  Q_RES  100 1% CHIP  pkg 0402LF  page 266 : A = VSENSE_PVCCIN_CPU0_DP ; B = PVCCIN_CPU0

(kicad_pcb
	(version 20260206)
	(generator "pcbnew")
	(generator_version "10.0")
	(general
		(thickness 1.6)
		(legacy_teardrops no)
	)
	(paper "A4")
	(title_block
		(title "03242023_DA0F0TMBIJ0_F0T_Motherboard_J_brd_V01_OCP.brd")
		(comment 1 "Grand Teton / footprints 4370-4371 of 6105")
	)
	(layers
		(0 "F.Cu" signal "TOP")
		(4 "In1.Cu" signal "GND")
		(6 "In2.Cu" signal "IN1")
		(8 "In3.Cu" signal "GND1")
		(10 "In4.Cu" signal "IN2")
		(12 "In5.Cu" signal "GND2")
		(14 "In6.Cu" signal "IN3")
		(16 "In7.Cu" signal "GND3")
		(18 "In8.Cu" signal "VCC")
		(20 "In9.Cu" signal "VCC1")
		(22 "In10.Cu" signal "GND4")
		(24 "In11.Cu" signal "IN4")
		(26 "In12.Cu" signal "GND5")
		(28 "In13.Cu" signal "IN5")
		(30 "In14.Cu" signal "GND6")
		(32 "In15.Cu" signal "IN6")
		(34 "In16.Cu" signal "GND7")
		(2 "B.Cu" signal "BOTTOM")
		(9 "F.Adhes" user "F.Adhesive")
		(11 "B.Adhes" user "B.Adhesive")
		(13 "F.Paste" user "Package Geometry/Pastemask Top")
		(15 "B.Paste" user "Package Geometry/Pastemask Bottom")
		(5 "F.SilkS" user "Ref Des/Silkscreen Top")
		(7 "B.SilkS" user "Ref Des/Silkscreen Bottom")
		(1 "F.Mask" user "Board Geometry/Soldermask Top")
		(3 "B.Mask" user "Board Geometry/Soldermask Bottom")
		(17 "Dwgs.User" user "User.Drawings")
		(19 "Cmts.User" user "User.Comments")
		(21 "Eco1.User" user "User.Eco1")
		(23 "Eco2.User" user "User.Eco2")
		(25 "Edge.Cuts" user "Board Geometry/Outline")
		(27 "Margin" user)
		(31 "F.CrtYd" user "Package Geometry/Place Bound Top")
		(29 "B.CrtYd" user "Package Geometry/Place Bound Bottom")
		(35 "F.Fab" user "Ref Des/Assembly Top")
		(33 "B.Fab" user "Ref Des/Assembly Bottom")
	)
	(footprint ""
		(layer "B.Cu")
		(at 275.157184 -193.669666 -90)
		(property "Reference" "R250"
			(at 0 0 90)
			(layer "B.SilkS")
			(hide yes)
			(effects
				(font
					(size 1.27 1.27)
				)
				(justify mirror)
			)
		)
		(property "Value" ""
			(at 0 0 90)
			(layer "B.Fab")
			(effects
				(font
					(size 1.27 1.27)
				)
				(justify mirror)
			)
		)
		(duplicate_pad_numbers_are_jumpers no)
		(fp_line
			(start -0.7874 0.4064)
			(end 0.7874 0.4064)
			(stroke
				(width 0.1524)
				(type default)
			)
			(layer "B.SilkS")
		)
		(fp_line
			(start 0.7874 0.4064)
			(end 0.7874 -0.4064)
			(stroke
				(width 0.1524)
				(type default)
			)
			(layer "B.SilkS")
		)
		(fp_line
			(start -0.7874 -0.4064)
			(end -0.7874 0.4064)
			(stroke
				(width 0.1524)
				(type default)
			)
			(layer "B.SilkS")
		)
		(fp_line
			(start 0.7874 -0.4064)
			(end -0.7874 -0.4064)
			(stroke
				(width 0.1524)
				(type default)
			)
			(layer "B.SilkS")
		)
		(fp_line
			(start -0.67945 0.3048)
			(end -0.120396 0.3048)
			(stroke
				(width 0.1)
				(type default)
			)
			(layer "B.Fab")
		)
		(fp_line
			(start -0.120396 0.3048)
			(end -0.120396 0.2794)
			(stroke
				(width 0.1)
				(type default)
			)
			(layer "B.Fab")
		)
		(fp_line
			(start 0.12065 0.3048)
			(end 0.67945 0.3048)
			(stroke
				(width 0.1)
				(type default)
			)
			(layer "B.Fab")
		)
		(fp_line
			(start 0.67945 0.3048)
			(end 0.67945 -0.305054)
			(stroke
				(width 0.1)
				(type default)
			)
			(layer "B.Fab")
		)
		(fp_line
			(start -0.120396 0.2794)
			(end 0.12065 0.2794)
			(stroke
				(width 0.1)
				(type default)
			)
			(layer "B.Fab")
		)
		(fp_line
			(start 0.12065 0.2794)
			(end 0.12065 0.3048)
			(stroke
				(width 0.1)
				(type default)
			)
			(layer "B.Fab")
		)
		(fp_line
			(start -0.12065 -0.2794)
			(end -0.12065 -0.3048)
			(stroke
				(width 0.1)
				(type default)
			)
			(layer "B.Fab")
		)
		(fp_line
			(start 0.12065 -0.2794)
			(end -0.12065 -0.2794)
			(stroke
				(width 0.1)
				(type default)
			)
			(layer "B.Fab")
		)
		(fp_line
			(start -0.67945 -0.3048)
			(end -0.67945 0.3048)
			(stroke
				(width 0.1)
				(type default)
			)
			(layer "B.Fab")
		)
		(fp_line
			(start -0.12065 -0.3048)
			(end -0.67945 -0.3048)
			(stroke
				(width 0.1)
				(type default)
			)
			(layer "B.Fab")
		)
		(fp_line
			(start 0.12065 -0.305054)
			(end 0.12065 -0.2794)
			(stroke
				(width 0.1)
				(type default)
			)
			(layer "B.Fab")
		)
		(fp_line
			(start 0.67945 -0.305054)
			(end 0.12065 -0.305054)
			(stroke
				(width 0.1)
				(type default)
			)
			(layer "B.Fab")
		)
		(pad "1" smd circle
			(at 0.40005 0 90)
			(size 0 0)
			(layers "B.Cu" "B.Mask" "B.Paste")
			(net "PVNN_TERM_CPU0")
		)
		(pad "2" smd circle
			(at -0.40005 0 90)
			(size 0 0)
			(layers "B.Cu" "B.Mask" "B.Paste")
			(net "FM_S3M_CPU0_LVC1_GPIO_1")
		)
	)
	(footprint ""
		(layer "B.Cu")
		(at 324.35292 -331.626718 90)
		(property "Reference" "PR531"
			(at 0 0 90)
			(layer "B.SilkS")
			(hide yes)
			(effects
				(font
					(size 1.27 1.27)
				)
				(justify mirror)
			)
		)
		(property "Value" ""
			(at 0 0 90)
			(layer "B.Fab")
			(effects
				(font
					(size 1.27 1.27)
				)
				(justify mirror)
			)
		)
		(duplicate_pad_numbers_are_jumpers no)
		(fp_line
			(start 0.7874 -0.4064)
			(end -0.7874 -0.4064)
			(stroke
				(width 0.1524)
				(type default)
			)
			(layer "B.SilkS")
		)
		(fp_line
			(start -0.7874 -0.4064)
			(end -0.7874 0.4064)
			(stroke
				(width 0.1524)
				(type default)
			)
			(layer "B.SilkS")
		)
		(fp_line
			(start 0.7874 0.4064)
			(end 0.7874 -0.4064)
			(stroke
				(width 0.1524)
				(type default)
			)
			(layer "B.SilkS")
		)
		(fp_line
			(start -0.7874 0.4064)
			(end 0.7874 0.4064)
			(stroke
				(width 0.1524)
				(type default)
			)
			(layer "B.SilkS")
		)
		(fp_line
			(start 0.67945 -0.305054)
			(end 0.12065 -0.305054)
			(stroke
				(width 0.1)
				(type default)
			)
			(layer "B.Fab")
		)
		(fp_line
			(start 0.12065 -0.305054)
			(end 0.12065 -0.2794)
			(stroke
				(width 0.1)
				(type default)
			)
			(layer "B.Fab")
		)
		(fp_line
			(start -0.12065 -0.3048)
			(end -0.67945 -0.3048)
			(stroke
				(width 0.1)
				(type default)
			)
			(layer "B.Fab")
		)
		(fp_line
			(start -0.67945 -0.3048)
			(end -0.67945 0.3048)
			(stroke
				(width 0.1)
				(type default)
			)
			(layer "B.Fab")
		)
		(fp_line
			(start 0.12065 -0.2794)
			(end -0.12065 -0.2794)
			(stroke
				(width 0.1)
				(type default)
			)
			(layer "B.Fab")
		)
		(fp_line
			(start -0.12065 -0.2794)
			(end -0.12065 -0.3048)
			(stroke
				(width 0.1)
				(type default)
			)
			(layer "B.Fab")
		)
		(fp_line
			(start 0.12065 0.2794)
			(end 0.12065 0.3048)
			(stroke
				(width 0.1)
				(type default)
			)
			(layer "B.Fab")
		)
		(fp_line
			(start -0.120396 0.2794)
			(end 0.12065 0.2794)
			(stroke
				(width 0.1)
				(type default)
			)
			(layer "B.Fab")
		)
		(fp_line
			(start 0.67945 0.3048)
			(end 0.67945 -0.305054)
			(stroke
				(width 0.1)
				(type default)
			)
			(layer "B.Fab")
		)
		(fp_line
			(start 0.12065 0.3048)
			(end 0.67945 0.3048)
			(stroke
				(width 0.1)
				(type default)
			)
			(layer "B.Fab")
		)
		(fp_line
			(start -0.120396 0.3048)
			(end -0.120396 0.2794)
			(stroke
				(width 0.1)
				(type default)
			)
			(layer "B.Fab")
		)
		(fp_line
			(start -0.67945 0.3048)
			(end -0.120396 0.3048)
			(stroke
				(width 0.1)
				(type default)
			)
			(layer "B.Fab")
		)
		(pad "1" smd circle
			(at 0.40005 0 270)
			(size 0 0)
			(layers "B.Cu" "B.Mask" "B.Paste")
			(net "VSENSE_PVCCIN_CPU0_DP")
		)
		(pad "2" smd circle
			(at -0.40005 0 270)
			(size 0 0)
			(layers "B.Cu" "B.Mask" "B.Paste")
			(net "PVCCIN_CPU0")
		)
	)
)
